(kicad_pcb
	(version 20260206)
	(generator "pcbnew")
	(generator_version "10.0")
	(general
		(thickness 1.6)
		(legacy_teardrops no)
	)
	(paper "A4")
	(title_block
		(title "panther-plus-userver — 13130-1b_20150205.brd")
		(comment 1 "Honey Badger (Wiwynn) / footprints 1441-1448 of 1509")
	)
	(layers
		(0 "F.Cu" signal "TOP")
		(4 "In1.Cu" signal "L2")
		(6 "In2.Cu" signal "L3")
		(8 "In3.Cu" signal "L4")
		(10 "In4.Cu" signal "L5")
		(12 "In5.Cu" signal "L6")
		(14 "In6.Cu" signal "L7")
		(16 "In7.Cu" signal "L8")
		(18 "In8.Cu" signal "L9")
		(20 "In9.Cu" signal "L10")
		(22 "In10.Cu" signal "L11")
		(2 "B.Cu" signal "BOTTOM")
		(9 "F.Adhes" user "F.Adhesive")
		(11 "B.Adhes" user "B.Adhesive")
		(13 "F.Paste" user "Package Geometry/Pastemask Top")
		(15 "B.Paste" user "Package Geometry/Pastemask Bottom")
		(5 "F.SilkS" user "Ref Des/Silkscreen Top")
		(7 "B.SilkS" user "Ref Des/Silkscreen Bottom")
		(1 "F.Mask" user "Board Geometry/Soldermask Top")
		(3 "B.Mask" user "Board Geometry/Soldermask Bottom")
		(17 "Dwgs.User" user "User.Drawings")
		(19 "Cmts.User" user "User.Comments")
		(21 "Eco1.User" user "User.Eco1")
		(23 "Eco2.User" user "User.Eco2")
		(25 "Edge.Cuts" user "Board Geometry/Outline")
		(27 "Margin" user)
		(31 "F.CrtYd" user "Package Geometry/Place Bound Top")
		(29 "B.CrtYd" user "Package Geometry/Place Bound Bottom")
		(35 "F.Fab" user "Ref Des/Assembly Top")
		(33 "B.Fab" user "Ref Des/Assembly Bottom")
	)
	(footprint ""
		(layer "B.Cu")
		(at 48.006 -28.194 180)
		(property "Reference" "R450"
			(at 0 0 0)
			(layer "B.SilkS")
			(hide yes)
			(effects
				(font
					(size 1.27 1.27)
				)
				(justify mirror)
			)
		)
		(property "Value" "4K7R2F-GP"
			(at -1.7907 -1.1176 180)
			(unlocked yes)
			(layer "B.Fab")
			(hide yes)
			(effects
				(font
					(size 1.016 1.016)
					(thickness 0.1524)
				)
				(justify mirror)
			)
		)
		(property "Device Type" "R402H16"
			(at -1.7907 -2.6416 180)
			(unlocked yes)
			(layer "B.Fab")
			(hide yes)
			(effects
				(font
					(size 1.016 1.016)
					(thickness 0.1524)
				)
				(justify mirror)
			)
		)
		(duplicate_pad_numbers_are_jumpers no)
		(fp_rect
			(start 0.381 0.8382)
			(end -0.381 -0.8382)
			(stroke
				(width 0)
				(type default)
			)
			(fill no)
			(layer "B.CrtYd")
		)
		(fp_rect
			(start 0.381 0.8382)
			(end -0.381 -0.8382)
			(stroke
				(width 0)
				(type default)
			)
			(fill no)
			(layer "B.Fab")
		)
		(pad "1" smd custom
			(at 0 -0.4318)
			(size 0.127 0.127)
			(layers "B.Cu" "B.Mask" "B.Paste")
			(net "CLK_GEN_PG")
			(options
				(clearance outline)
				(anchor circle)
			)
			(primitives
				(gr_poly
					(pts
						(arc
							(start -0.2032 0.2794)
							(mid -0.239121 0.264521)
							(end -0.254 0.2286)
						)
						(arc
							(start -0.254 -0.2286)
							(mid -0.239121 -0.264521)
							(end -0.2032 -0.2794)
						)
						(arc
							(start 0.2032 -0.2794)
							(mid 0.239121 -0.264521)
							(end 0.254 -0.2286)
						)
						(arc
							(start 0.254 0.2286)
							(mid 0.239121 0.264521)
							(end 0.2032 0.2794)
						)
					)
					(width 0)
					(fill yes)
				)
			)
		)
		(pad "2" smd custom
			(at 0 0.4318)
			(size 0.127 0.127)
			(layers "B.Cu" "B.Mask" "B.Paste")
			(net "GND")
			(options
				(clearance outline)
				(anchor circle)
			)
			(primitives
				(gr_poly
					(pts
						(arc
							(start -0.2032 0.2794)
							(mid -0.239121 0.264521)
							(end -0.254 0.2286)
						)
						(arc
							(start -0.254 -0.2286)
							(mid -0.239121 -0.264521)
							(end -0.2032 -0.2794)
						)
						(arc
							(start 0.2032 -0.2794)
							(mid 0.239121 -0.264521)
							(end 0.254 -0.2286)
						)
						(arc
							(start 0.254 0.2286)
							(mid 0.239121 0.264521)
							(end 0.2032 0.2794)
						)
					)
					(width 0)
					(fill yes)
				)
			)
		)
	)
	(footprint ""
		(layer "B.Cu")
		(at 91.186 -46.101 180)
		(property "Reference" "C143"
			(at 0 0 0)
			(layer "B.SilkS")
			(hide yes)
			(effects
				(font
					(size 1.27 1.27)
				)
				(justify mirror)
			)
		)
		(property "Value" "SCD1U16V2JX-1-GP"
			(at -1.1811 -2.7051 180)
			(unlocked yes)
			(layer "B.Fab")
			(hide yes)
			(effects
				(font
					(size 1.016 1.016)
					(thickness 0.1524)
				)
				(justify mirror)
			)
		)
		(property "Device Type" "C402H22"
			(at -1.1811 -4.2291 180)
			(unlocked yes)
			(layer "B.Fab")
			(hide yes)
			(effects
				(font
					(size 1.016 1.016)
					(thickness 0.1524)
				)
				(justify mirror)
			)
		)
		(duplicate_pad_numbers_are_jumpers no)
		(fp_rect
			(start 0.381 0.7366)
			(end -0.381 -0.7366)
			(stroke
				(width 0)
				(type default)
			)
			(fill no)
			(layer "B.CrtYd")
		)
		(fp_rect
			(start 0.381 0.7366)
			(end -0.381 -0.7366)
			(stroke
				(width 0)
				(type default)
			)
			(fill no)
			(layer "B.Fab")
		)
		(pad "1" smd custom
			(at 0 -0.4572)
			(size 0.1143 0.1143)
			(layers "B.Cu" "B.Mask" "B.Paste")
			(net "P3V3_CPU")
			(options
				(clearance outline)
				(anchor circle)
			)
			(primitives
				(gr_poly
					(pts
						(arc
							(start -0.254 0.1778)
							(mid -0.239121 0.213721)
							(end -0.2032 0.2286)
						)
						(arc
							(start 0.2032 0.2286)
							(mid 0.239121 0.213721)
							(end 0.254 0.1778)
						)
						(arc
							(start 0.254 -0.1778)
							(mid 0.239121 -0.213721)
							(end 0.2032 -0.2286)
						)
						(arc
							(start -0.2032 -0.2286)
							(mid -0.239121 -0.213721)
							(end -0.254 -0.1778)
						)
					)
					(width 0)
					(fill yes)
				)
			)
		)
		(pad "2" smd custom
			(at 0 0.4572)
			(size 0.1143 0.1143)
			(layers "B.Cu" "B.Mask" "B.Paste")
			(net "GND")
			(options
				(clearance outline)
				(anchor circle)
			)
			(primitives
				(gr_poly
					(pts
						(arc
							(start -0.254 0.1778)
							(mid -0.239121 0.213721)
							(end -0.2032 0.2286)
						)
						(arc
							(start 0.2032 0.2286)
							(mid 0.239121 0.213721)
							(end 0.254 0.1778)
						)
						(arc
							(start 0.254 -0.1778)
							(mid 0.239121 -0.213721)
							(end 0.2032 -0.2286)
						)
						(arc
							(start -0.2032 -0.2286)
							(mid -0.239121 -0.213721)
							(end -0.254 -0.1778)
						)
					)
					(width 0)
					(fill yes)
				)
			)
		)
	)
	(footprint ""
		(layer "B.Cu")
		(at 144.399 -45.466 -90)
		(property "Reference" "R336"
			(at 0 0 90)
			(layer "B.SilkS")
			(hide yes)
			(effects
				(font
					(size 1.27 1.27)
				)
				(justify mirror)
			)
		)
		(property "Value" "1KR2F-3-GP"
			(at -0.064008 -3.993896 270)
			(unlocked yes)
			(layer "B.Fab")
			(hide yes)
			(effects
				(font
					(size 1.016 1.016)
					(thickness 0.1524)
				)
				(justify mirror)
			)
		)
		(property "Device Type" "R402H16"
			(at -0.064008 -5.517896 270)
			(unlocked yes)
			(layer "B.Fab")
			(hide yes)
			(effects
				(font
					(size 1.016 1.016)
					(thickness 0.1524)
				)
				(justify mirror)
			)
		)
		(duplicate_pad_numbers_are_jumpers no)
		(fp_rect
			(start 0.381 0.8382)
			(end -0.381 -0.8382)
			(stroke
				(width 0)
				(type default)
			)
			(fill no)
			(layer "B.CrtYd")
		)
		(fp_rect
			(start 0.381 0.8382)
			(end -0.381 -0.8382)
			(stroke
				(width 0)
				(type default)
			)
			(fill no)
			(layer "B.Fab")
		)
		(pad "1" smd custom
			(at 0 -0.4318 90)
			(size 0.127 0.127)
			(layers "B.Cu" "B.Mask" "B.Paste")
			(net "JTAG_PLD_TCK")
			(options
				(clearance outline)
				(anchor circle)
			)
			(primitives
				(gr_poly
					(pts
						(arc
							(start -0.2032 0.2794)
							(mid -0.239121 0.264521)
							(end -0.254 0.2286)
						)
						(arc
							(start -0.254 -0.2286)
							(mid -0.239121 -0.264521)
							(end -0.2032 -0.2794)
						)
						(arc
							(start 0.2032 -0.2794)
							(mid 0.239121 -0.264521)
							(end 0.254 -0.2286)
						)
						(arc
							(start 0.254 0.2286)
							(mid 0.239121 0.264521)
							(end 0.2032 0.2794)
						)
					)
					(width 0)
					(fill yes)
				)
			)
		)
		(pad "2" smd custom
			(at 0 0.4318 90)
			(size 0.127 0.127)
			(layers "B.Cu" "B.Mask" "B.Paste")
			(net "GND")
			(options
				(clearance outline)
				(anchor circle)
			)
			(primitives
				(gr_poly
					(pts
						(arc
							(start -0.2032 0.2794)
							(mid -0.239121 0.264521)
							(end -0.254 0.2286)
						)
						(arc
							(start -0.254 -0.2286)
							(mid -0.239121 -0.264521)
							(end -0.2032 -0.2794)
						)
						(arc
							(start 0.2032 -0.2794)
							(mid 0.239121 -0.264521)
							(end 0.254 -0.2286)
						)
						(arc
							(start 0.254 0.2286)
							(mid 0.239121 0.264521)
							(end 0.2032 0.2794)
						)
					)
					(width 0)
					(fill yes)
				)
			)
		)
	)
	(footprint ""
		(layer "B.Cu")
		(at 201.295 -38.6842 90)
		(property "Reference" "LED9"
			(at 0 0 90)
			(layer "B.SilkS")
			(hide yes)
			(effects
				(font
					(size 1.27 1.27)
				)
				(justify mirror)
			)
		)
		(property "Value" "LED-YG-51-GP"
			(at 0.0381 -2.6162 90)
			(unlocked yes)
			(layer "B.Fab")
			(hide yes)
			(effects
				(font
					(size 1.016 1.016)
					(thickness 0.1524)
				)
				(justify mirror)
			)
		)
		(property "Device Type" "LED1608AKH40"
			(at 0.0381 -4.1402 90)
			(unlocked yes)
			(layer "B.Fab")
			(hide yes)
			(effects
				(font
					(size 1.016 1.016)
					(thickness 0.1524)
				)
				(justify mirror)
			)
		)
		(duplicate_pad_numbers_are_jumpers no)
		(fp_line
			(start 0.5334 1.3081)
			(end -0.5334 1.3081)
			(stroke
				(width 0.254)
				(type default)
			)
			(layer "B.SilkS")
		)
		(fp_rect
			(start 0.6604 1.1811)
			(end -0.6604 -1.1811)
			(stroke
				(width 0)
				(type default)
			)
			(fill no)
			(layer "B.CrtYd")
		)
		(fp_rect
			(start 0.6604 1.1811)
			(end -0.6604 -1.1811)
			(stroke
				(width 0)
				(type default)
			)
			(fill no)
			(layer "B.Fab")
		)
		(pad "A" smd rect
			(at 0 -0.652526 270)
			(size 1.0668 0.8128)
			(layers "B.Cu" "B.Mask" "B.Paste")
			(net "PORT80_R_BIT4")
		)
		(pad "K" smd rect
			(at 0 0.652526 270)
			(size 1.0668 0.8128)
			(layers "B.Cu" "B.Mask" "B.Paste")
			(net "PORT80_BIT4")
		)
	)
	(footprint ""
		(layer "B.Cu")
		(at 118.11 -6.096 90)
		(property "Reference" "C335"
			(at 0 0 90)
			(layer "B.SilkS")
			(hide yes)
			(effects
				(font
					(size 1.27 1.27)
				)
				(justify mirror)
			)
		)
		(property "Value" "SCD1U10V2KX-5GP"
			(at -1.8923 -1.2065 90)
			(unlocked yes)
			(layer "B.Fab")
			(hide yes)
			(effects
				(font
					(size 1.016 1.016)
					(thickness 0.1524)
				)
				(justify mirror)
			)
		)
		(property "Device Type" "C402H22"
			(at -1.8923 -2.7305 90)
			(unlocked yes)
			(layer "B.Fab")
			(hide yes)
			(effects
				(font
					(size 1.016 1.016)
					(thickness 0.1524)
				)
				(justify mirror)
			)
		)
		(duplicate_pad_numbers_are_jumpers no)
		(fp_rect
			(start 0.381 0.7366)
			(end -0.381 -0.7366)
			(stroke
				(width 0)
				(type default)
			)
			(fill no)
			(layer "B.CrtYd")
		)
		(fp_rect
			(start 0.381 0.7366)
			(end -0.381 -0.7366)
			(stroke
				(width 0)
				(type default)
			)
			(fill no)
			(layer "B.Fab")
		)
		(pad "1" smd custom
			(at 0 -0.4572 270)
			(size 0.1143 0.1143)
			(layers "B.Cu" "B.Mask" "B.Paste")
			(net "P3V3")
			(options
				(clearance outline)
				(anchor circle)
			)
			(primitives
				(gr_poly
					(pts
						(arc
							(start -0.254 0.1778)
							(mid -0.239121 0.213721)
							(end -0.2032 0.2286)
						)
						(arc
							(start 0.2032 0.2286)
							(mid 0.239121 0.213721)
							(end 0.254 0.1778)
						)
						(arc
							(start 0.254 -0.1778)
							(mid 0.239121 -0.213721)
							(end 0.2032 -0.2286)
						)
						(arc
							(start -0.2032 -0.2286)
							(mid -0.239121 -0.213721)
							(end -0.254 -0.1778)
						)
					)
					(width 0)
					(fill yes)
				)
			)
		)
		(pad "2" smd custom
			(at 0 0.4572 270)
			(size 0.1143 0.1143)
			(layers "B.Cu" "B.Mask" "B.Paste")
			(net "GND")
			(options
				(clearance outline)
				(anchor circle)
			)
			(primitives
				(gr_poly
					(pts
						(arc
							(start -0.254 0.1778)
							(mid -0.239121 0.213721)
							(end -0.2032 0.2286)
						)
						(arc
							(start 0.2032 0.2286)
							(mid 0.239121 0.213721)
							(end 0.254 0.1778)
						)
						(arc
							(start 0.254 -0.1778)
							(mid 0.239121 -0.213721)
							(end 0.2032 -0.2286)
						)
						(arc
							(start -0.2032 -0.2286)
							(mid -0.239121 -0.213721)
							(end -0.254 -0.1778)
						)
					)
					(width 0)
					(fill yes)
				)
			)
		)
	)
	(footprint ""
		(layer "B.Cu")
		(at 19.812 -61.087 180)
		(property "Reference" "PR2"
			(at 0 0 0)
			(layer "B.SilkS")
			(hide yes)
			(effects
				(font
					(size 1.27 1.27)
				)
				(justify mirror)
			)
		)
		(property "Value" "1KR2F-3-GP"
			(at -1.7907 -1.1176 180)
			(unlocked yes)
			(layer "B.Fab")
			(hide yes)
			(effects
				(font
					(size 1.016 1.016)
					(thickness 0.1524)
				)
				(justify mirror)
			)
		)
		(property "Device Type" "R402H16"
			(at -1.7907 -2.6416 180)
			(unlocked yes)
			(layer "B.Fab")
			(hide yes)
			(effects
				(font
					(size 1.016 1.016)
					(thickness 0.1524)
				)
				(justify mirror)
			)
		)
		(duplicate_pad_numbers_are_jumpers no)
		(fp_rect
			(start 0.381 0.8382)
			(end -0.381 -0.8382)
			(stroke
				(width 0)
				(type default)
			)
			(fill no)
			(layer "B.CrtYd")
		)
		(fp_rect
			(start 0.381 0.8382)
			(end -0.381 -0.8382)
			(stroke
				(width 0)
				(type default)
			)
			(fill no)
			(layer "B.Fab")
		)
		(pad "1" smd custom
			(at 0 -0.4318)
			(size 0.127 0.127)
			(layers "B.Cu" "B.Mask" "B.Paste")
			(net "VR_PVNN_FB")
			(options
				(clearance outline)
				(anchor circle)
			)
			(primitives
				(gr_poly
					(pts
						(arc
							(start -0.2032 0.2794)
							(mid -0.239121 0.264521)
							(end -0.254 0.2286)
						)
						(arc
							(start -0.254 -0.2286)
							(mid -0.239121 -0.264521)
							(end -0.2032 -0.2794)
						)
						(arc
							(start 0.2032 -0.2794)
							(mid 0.239121 -0.264521)
							(end 0.254 -0.2286)
						)
						(arc
							(start 0.254 0.2286)
							(mid 0.239121 0.264521)
							(end 0.2032 0.2794)
						)
					)
					(width 0)
					(fill yes)
				)
			)
		)
		(pad "2" smd custom
			(at 0 0.4318)
			(size 0.127 0.127)
			(layers "B.Cu" "B.Mask" "B.Paste")
			(net "VR_PVNN_FB_RC2")
			(options
				(clearance outline)
				(anchor circle)
			)
			(primitives
				(gr_poly
					(pts
						(arc
							(start -0.2032 0.2794)
							(mid -0.239121 0.264521)
							(end -0.254 0.2286)
						)
						(arc
							(start -0.254 -0.2286)
							(mid -0.239121 -0.264521)
							(end -0.2032 -0.2794)
						)
						(arc
							(start 0.2032 -0.2794)
							(mid 0.239121 -0.264521)
							(end 0.254 -0.2286)
						)
						(arc
							(start 0.254 0.2286)
							(mid 0.239121 0.264521)
							(end 0.2032 0.2794)
						)
					)
					(width 0)
					(fill yes)
				)
			)
		)
	)
	(footprint ""
		(layer "B.Cu")
		(at 89.154 -46.228 180)
		(property "Reference" "R298"
			(at 0 0 0)
			(layer "B.SilkS")
			(hide yes)
			(effects
				(font
					(size 1.27 1.27)
				)
				(justify mirror)
			)
		)
		(property "Value" "10KR2F-2-GP"
			(at -0.064008 -3.993896 180)
			(unlocked yes)
			(layer "B.Fab")
			(hide yes)
			(effects
				(font
					(size 1.016 1.016)
					(thickness 0.1524)
				)
				(justify mirror)
			)
		)
		(property "Device Type" "R402H16"
			(at -0.064008 -5.517896 180)
			(unlocked yes)
			(layer "B.Fab")
			(hide yes)
			(effects
				(font
					(size 1.016 1.016)
					(thickness 0.1524)
				)
				(justify mirror)
			)
		)
		(duplicate_pad_numbers_are_jumpers no)
		(fp_rect
			(start 0.381 0.8382)
			(end -0.381 -0.8382)
			(stroke
				(width 0)
				(type default)
			)
			(fill no)
			(layer "B.CrtYd")
		)
		(fp_rect
			(start 0.381 0.8382)
			(end -0.381 -0.8382)
			(stroke
				(width 0)
				(type default)
			)
			(fill no)
			(layer "B.Fab")
		)
		(pad "1" smd custom
			(at 0 -0.4318)
			(size 0.127 0.127)
			(layers "B.Cu" "B.Mask" "B.Paste")
			(net "IRQ_CPU_SERIAL")
			(options
				(clearance outline)
				(anchor circle)
			)
			(primitives
				(gr_poly
					(pts
						(arc
							(start -0.2032 0.2794)
							(mid -0.239121 0.264521)
							(end -0.254 0.2286)
						)
						(arc
							(start -0.254 -0.2286)
							(mid -0.239121 -0.264521)
							(end -0.2032 -0.2794)
						)
						(arc
							(start 0.2032 -0.2794)
							(mid 0.239121 -0.264521)
							(end 0.254 -0.2286)
						)
						(arc
							(start 0.254 0.2286)
							(mid 0.239121 0.264521)
							(end 0.2032 0.2794)
						)
					)
					(width 0)
					(fill yes)
				)
			)
		)
		(pad "2" smd custom
			(at 0 0.4318)
			(size 0.127 0.127)
			(layers "B.Cu" "B.Mask" "B.Paste")
			(net "GND")
			(options
				(clearance outline)
				(anchor circle)
			)
			(primitives
				(gr_poly
					(pts
						(arc
							(start -0.2032 0.2794)
							(mid -0.239121 0.264521)
							(end -0.254 0.2286)
						)
						(arc
							(start -0.254 -0.2286)
							(mid -0.239121 -0.264521)
							(end -0.2032 -0.2794)
						)
						(arc
							(start 0.2032 -0.2794)
							(mid 0.239121 -0.264521)
							(end 0.254 -0.2286)
						)
						(arc
							(start 0.254 0.2286)
							(mid 0.239121 0.264521)
							(end 0.2032 0.2794)
						)
					)
					(width 0)
					(fill yes)
				)
			)
		)
	)
	(footprint ""
		(layer "B.Cu")
		(at 18.923 -21.463 -90)
		(property "Reference" "PR99"
			(at 0 0 90)
			(layer "B.SilkS")
			(hide yes)
			(effects
				(font
					(size 1.27 1.27)
				)
				(justify mirror)
			)
		)
		(property "Value" "0R2J-2-GP"
			(at -1.7907 -1.1176 270)
			(unlocked yes)
			(layer "B.Fab")
			(hide yes)
			(effects
				(font
					(size 1.016 1.016)
					(thickness 0.1524)
				)
				(justify mirror)
			)
		)
		(property "Device Type" "R402H16"
			(at -1.7907 -2.6416 270)
			(unlocked yes)
			(layer "B.Fab")
			(hide yes)
			(effects
				(font
					(size 1.016 1.016)
					(thickness 0.1524)
				)
				(justify mirror)
			)
		)
		(duplicate_pad_numbers_are_jumpers no)
		(fp_rect
			(start 0.381 0.8382)
			(end -0.381 -0.8382)
			(stroke
				(width 0)
				(type default)
			)
			(fill no)
			(layer "B.CrtYd")
		)
		(fp_rect
			(start 0.381 0.8382)
			(end -0.381 -0.8382)
			(stroke
				(width 0)
				(type default)
			)
			(fill no)
			(layer "B.Fab")
		)
		(pad "1" smd custom
			(at 0 -0.4318 90)
			(size 0.127 0.127)
			(layers "B.Cu" "B.Mask" "B.Paste")
			(net "PWRGD_P1V35_PG")
			(options
				(clearance outline)
				(anchor circle)
			)
			(primitives
				(gr_poly
					(pts
						(arc
							(start -0.2032 0.2794)
							(mid -0.239121 0.264521)
							(end -0.254 0.2286)
						)
						(arc
							(start -0.254 -0.2286)
							(mid -0.239121 -0.264521)
							(end -0.2032 -0.2794)
						)
						(arc
							(start 0.2032 -0.2794)
							(mid 0.239121 -0.264521)
							(end 0.254 -0.2286)
						)
						(arc
							(start 0.254 0.2286)
							(mid 0.239121 0.264521)
							(end 0.2032 0.2794)
						)
					)
					(width 0)
					(fill yes)
				)
			)
		)
		(pad "2" smd custom
			(at 0 0.4318 90)
			(size 0.127 0.127)
			(layers "B.Cu" "B.Mask" "B.Paste")
			(net "P1V0_EN")
			(options
				(clearance outline)
				(anchor circle)
			)
			(primitives
				(gr_poly
					(pts
						(arc
							(start -0.2032 0.2794)
							(mid -0.239121 0.264521)
							(end -0.254 0.2286)
						)
						(arc
							(start -0.254 -0.2286)
							(mid -0.239121 -0.264521)
							(end -0.2032 -0.2794)
						)
						(arc
							(start 0.2032 -0.2794)
							(mid 0.239121 -0.264521)
							(end 0.254 -0.2286)
						)
						(arc
							(start 0.254 0.2286)
							(mid 0.239121 0.264521)
							(end 0.2032 0.2794)
						)
					)
					(width 0)
					(fill yes)
				)
			)
		)
	)
)
